(kicad_pcb
	(version 20260206)
	(generator "pcbnew")
	(generator_version "10.0")
	(general
		(thickness 1.6)
		(legacy_teardrops no)
	)
	(paper "A4")
	(title_block
		(title "12092022_DA0F0TFB6D0_F0T_FAN_BOARD_MP5048_D_brd_v02_OCP.brd")
		(comment 1 "Grand Teton / footprints 482-486 of 924")
	)
	(layers
		(0 "F.Cu" signal "TOP")
		(4 "In1.Cu" signal "GND")
		(6 "In2.Cu" signal "IN1")
		(8 "In3.Cu" signal "IN2")
		(10 "In4.Cu" signal "GND1")
		(2 "B.Cu" signal "BOTTOM")
		(9 "F.Adhes" user "F.Adhesive")
		(11 "B.Adhes" user "B.Adhesive")
		(13 "F.Paste" user "Package Geometry/Pastemask Top")
		(15 "B.Paste" user "Package Geometry/Pastemask Bottom")
		(5 "F.SilkS" user "Ref Des/Silkscreen Top")
		(7 "B.SilkS" user "Ref Des/Silkscreen Bottom")
		(1 "F.Mask" user "Board Geometry/Soldermask Top")
		(3 "B.Mask" user "Board Geometry/Soldermask Bottom")
		(17 "Dwgs.User" user "User.Drawings")
		(19 "Cmts.User" user "User.Comments")
		(21 "Eco1.User" user "User.Eco1")
		(23 "Eco2.User" user "User.Eco2")
		(25 "Edge.Cuts" user "Board Geometry/Outline")
		(27 "Margin" user)
		(31 "F.CrtYd" user "Package Geometry/Place Bound Top")
		(29 "B.CrtYd" user "Package Geometry/Place Bound Bottom")
		(35 "F.Fab" user "Ref Des/Assembly Top")
		(33 "B.Fab" user "Ref Des/Assembly Bottom")
	)
	(footprint ""
		(layer "F.Cu")
		(at 48.387 -98.552)
		(property "Reference" "Q11"
			(at 0.16764 -2.42951 0)
			(unlocked yes)
			(layer "F.SilkS")
			(effects
				(font
					(size 0.7874 0.5842)
					(thickness 0.1524)
				)
				(justify left)
			)
		)
		(property "Value" ""
			(at 0 0 0)
			(layer "F.Fab")
			(effects
				(font
					(size 1.27 1.27)
				)
			)
		)
		(duplicate_pad_numbers_are_jumpers no)
		(fp_line
			(start -1.905 -1.651)
			(end 1.905 -1.651)
			(stroke
				(width 0.1524)
				(type default)
			)
			(layer "F.SilkS")
		)
		(fp_line
			(start -1.905 1.651)
			(end -1.905 -1.651)
			(stroke
				(width 0.1524)
				(type default)
			)
			(layer "F.SilkS")
		)
		(fp_line
			(start 1.905 -1.651)
			(end 1.905 1.651)
			(stroke
				(width 0.1524)
				(type default)
			)
			(layer "F.SilkS")
		)
		(fp_line
			(start 1.905 1.651)
			(end -1.905 1.651)
			(stroke
				(width 0.1524)
				(type default)
			)
			(layer "F.SilkS")
		)
		(fp_line
			(start -1.249934 -1.169924)
			(end -0.6985 -1.169924)
			(stroke
				(width 0.1)
				(type default)
			)
			(layer "F.Fab")
		)
		(fp_line
			(start -1.249934 -0.729996)
			(end -1.249934 -1.169924)
			(stroke
				(width 0.1)
				(type default)
			)
			(layer "F.Fab")
		)
		(fp_line
			(start -1.249934 0.729996)
			(end -0.6985 0.729996)
			(stroke
				(width 0.1)
				(type default)
			)
			(layer "F.Fab")
		)
		(fp_line
			(start -1.249934 1.169924)
			(end -1.249934 0.729996)
			(stroke
				(width 0.1)
				(type default)
			)
			(layer "F.Fab")
		)
		(fp_line
			(start -0.6985 -1.524)
			(end 0.6985 -1.524)
			(stroke
				(width 0.1)
				(type default)
			)
			(layer "F.Fab")
		)
		(fp_line
			(start -0.6985 -1.169924)
			(end -0.6985 -1.524)
			(stroke
				(width 0.1)
				(type default)
			)
			(layer "F.Fab")
		)
		(fp_line
			(start -0.6985 -0.729996)
			(end -1.249934 -0.729996)
			(stroke
				(width 0.1)
				(type default)
			)
			(layer "F.Fab")
		)
		(fp_line
			(start -0.6985 0.729996)
			(end -0.6985 -0.729996)
			(stroke
				(width 0.1)
				(type default)
			)
			(layer "F.Fab")
		)
		(fp_line
			(start -0.6985 1.169924)
			(end -1.249934 1.169924)
			(stroke
				(width 0.1)
				(type default)
			)
			(layer "F.Fab")
		)
		(fp_line
			(start -0.6985 1.524)
			(end -0.6985 1.169924)
			(stroke
				(width 0.1)
				(type default)
			)
			(layer "F.Fab")
		)
		(fp_line
			(start 0.6985 -1.524)
			(end 0.6985 -0.219964)
			(stroke
				(width 0.1)
				(type default)
			)
			(layer "F.Fab")
		)
		(fp_line
			(start 0.6985 -0.219964)
			(end 1.249934 -0.219964)
			(stroke
				(width 0.1)
				(type default)
			)
			(layer "F.Fab")
		)
		(fp_line
			(start 0.6985 0.219964)
			(end 0.6985 1.524)
			(stroke
				(width 0.1)
				(type default)
			)
			(layer "F.Fab")
		)
		(fp_line
			(start 0.6985 1.524)
			(end -0.6985 1.524)
			(stroke
				(width 0.1)
				(type default)
			)
			(layer "F.Fab")
		)
		(fp_line
			(start 1.249934 -0.219964)
			(end 1.249934 0.219964)
			(stroke
				(width 0.1)
				(type default)
			)
			(layer "F.Fab")
		)
		(fp_line
			(start 1.249934 0.219964)
			(end 0.6985 0.219964)
			(stroke
				(width 0.1)
				(type default)
			)
			(layer "F.Fab")
		)
		(fp_rect
			(start -0.6985 1.524)
			(end 0.6985 -1.524)
			(stroke
				(width 0)
				(type default)
			)
			(fill no)
			(layer "F.Fab")
		)
		(pad "D" smd rect
			(at 1.1176 0 270)
			(size 1.016 1.27)
			(layers "F.Cu" "F.Mask" "F.Paste")
			(net "P12V_LED_FAN2")
		)
		(pad "G" smd rect
			(at -1.1176 -1.016 270)
			(size 1.016 1.27)
			(layers "F.Cu" "F.Mask" "F.Paste")
			(net "U407_D1")
		)
		(pad "S" smd rect
			(at -1.1176 1.016 270)
			(size 1.016 1.27)
			(layers "F.Cu" "F.Mask" "F.Paste")
			(net "P12V_LED")
		)
	)
	(footprint ""
		(layer "F.Cu")
		(at 14.0589 -127.127 180)
		(property "Reference" "R5589"
			(at 0 0 180)
			(layer "F.SilkS")
			(hide yes)
			(effects
				(font
					(size 1.27 1.27)
				)
			)
		)
		(property "Value" ""
			(at 0 0 180)
			(layer "F.Fab")
			(effects
				(font
					(size 1.27 1.27)
				)
			)
		)
		(duplicate_pad_numbers_are_jumpers no)
		(fp_line
			(start 0.7874 0.4064)
			(end -0.7874 0.4064)
			(stroke
				(width 0.1524)
				(type default)
			)
			(layer "F.SilkS")
		)
		(fp_line
			(start 0.7874 -0.4064)
			(end 0.7874 0.4064)
			(stroke
				(width 0.1524)
				(type default)
			)
			(layer "F.SilkS")
		)
		(fp_line
			(start -0.7874 0.4064)
			(end -0.7874 -0.4064)
			(stroke
				(width 0.1524)
				(type default)
			)
			(layer "F.SilkS")
		)
		(fp_line
			(start -0.7874 -0.4064)
			(end 0.7874 -0.4064)
			(stroke
				(width 0.1524)
				(type default)
			)
			(layer "F.SilkS")
		)
		(fp_line
			(start 0.67945 0.3048)
			(end 0.120396 0.3048)
			(stroke
				(width 0.1)
				(type default)
			)
			(layer "F.Fab")
		)
		(fp_line
			(start 0.67945 -0.3048)
			(end 0.67945 0.3048)
			(stroke
				(width 0.1)
				(type default)
			)
			(layer "F.Fab")
		)
		(fp_line
			(start 0.12065 -0.2794)
			(end 0.12065 -0.3048)
			(stroke
				(width 0.1)
				(type default)
			)
			(layer "F.Fab")
		)
		(fp_line
			(start 0.12065 -0.3048)
			(end 0.67945 -0.3048)
			(stroke
				(width 0.1)
				(type default)
			)
			(layer "F.Fab")
		)
		(fp_line
			(start 0.120396 0.3048)
			(end 0.120396 0.2794)
			(stroke
				(width 0.1)
				(type default)
			)
			(layer "F.Fab")
		)
		(fp_line
			(start 0.120396 0.2794)
			(end -0.12065 0.2794)
			(stroke
				(width 0.1)
				(type default)
			)
			(layer "F.Fab")
		)
		(fp_line
			(start -0.12065 0.3048)
			(end -0.67945 0.3048)
			(stroke
				(width 0.1)
				(type default)
			)
			(layer "F.Fab")
		)
		(fp_line
			(start -0.12065 0.2794)
			(end -0.12065 0.3048)
			(stroke
				(width 0.1)
				(type default)
			)
			(layer "F.Fab")
		)
		(fp_line
			(start -0.12065 -0.2794)
			(end 0.12065 -0.2794)
			(stroke
				(width 0.1)
				(type default)
			)
			(layer "F.Fab")
		)
		(fp_line
			(start -0.12065 -0.305054)
			(end -0.12065 -0.2794)
			(stroke
				(width 0.1)
				(type default)
			)
			(layer "F.Fab")
		)
		(fp_line
			(start -0.67945 0.3048)
			(end -0.67945 -0.305054)
			(stroke
				(width 0.1)
				(type default)
			)
			(layer "F.Fab")
		)
		(fp_line
			(start -0.67945 -0.305054)
			(end -0.12065 -0.305054)
			(stroke
				(width 0.1)
				(type default)
			)
			(layer "F.Fab")
		)
		(pad "1" smd rect
			(at -0.40005 0)
			(size 0.4572 0.508)
			(layers "F.Cu" "F.Mask" "F.Paste")
			(net "FAN_5_PWM")
		)
		(pad "2" smd rect
			(at 0.40005 0)
			(size 0.4572 0.508)
			(layers "F.Cu" "F.Mask" "F.Paste")
			(net "FAN_5_PWM_R2")
		)
	)
	(footprint ""
		(layer "F.Cu")
		(at 20.828 -171.704 180)
		(property "Reference" "R5670"
			(at 0 0 180)
			(layer "F.SilkS")
			(hide yes)
			(effects
				(font
					(size 1.27 1.27)
				)
			)
		)
		(property "Value" ""
			(at 0 0 180)
			(layer "F.Fab")
			(effects
				(font
					(size 1.27 1.27)
				)
			)
		)
		(duplicate_pad_numbers_are_jumpers no)
		(fp_line
			(start 0.7874 0.4064)
			(end -0.7874 0.4064)
			(stroke
				(width 0.1524)
				(type default)
			)
			(layer "F.SilkS")
		)
		(fp_line
			(start 0.7874 -0.4064)
			(end 0.7874 0.4064)
			(stroke
				(width 0.1524)
				(type default)
			)
			(layer "F.SilkS")
		)
		(fp_line
			(start -0.7874 0.4064)
			(end -0.7874 -0.4064)
			(stroke
				(width 0.1524)
				(type default)
			)
			(layer "F.SilkS")
		)
		(fp_line
			(start -0.7874 -0.4064)
			(end 0.7874 -0.4064)
			(stroke
				(width 0.1524)
				(type default)
			)
			(layer "F.SilkS")
		)
		(fp_line
			(start 0.67945 0.3048)
			(end 0.120396 0.3048)
			(stroke
				(width 0.1)
				(type default)
			)
			(layer "F.Fab")
		)
		(fp_line
			(start 0.67945 -0.3048)
			(end 0.67945 0.3048)
			(stroke
				(width 0.1)
				(type default)
			)
			(layer "F.Fab")
		)
		(fp_line
			(start 0.12065 -0.2794)
			(end 0.12065 -0.3048)
			(stroke
				(width 0.1)
				(type default)
			)
			(layer "F.Fab")
		)
		(fp_line
			(start 0.12065 -0.3048)
			(end 0.67945 -0.3048)
			(stroke
				(width 0.1)
				(type default)
			)
			(layer "F.Fab")
		)
		(fp_line
			(start 0.120396 0.3048)
			(end 0.120396 0.2794)
			(stroke
				(width 0.1)
				(type default)
			)
			(layer "F.Fab")
		)
		(fp_line
			(start 0.120396 0.2794)
			(end -0.12065 0.2794)
			(stroke
				(width 0.1)
				(type default)
			)
			(layer "F.Fab")
		)
		(fp_line
			(start -0.12065 0.3048)
			(end -0.67945 0.3048)
			(stroke
				(width 0.1)
				(type default)
			)
			(layer "F.Fab")
		)
		(fp_line
			(start -0.12065 0.2794)
			(end -0.12065 0.3048)
			(stroke
				(width 0.1)
				(type default)
			)
			(layer "F.Fab")
		)
		(fp_line
			(start -0.12065 -0.2794)
			(end 0.12065 -0.2794)
			(stroke
				(width 0.1)
				(type default)
			)
			(layer "F.Fab")
		)
		(fp_line
			(start -0.12065 -0.305054)
			(end -0.12065 -0.2794)
			(stroke
				(width 0.1)
				(type default)
			)
			(layer "F.Fab")
		)
		(fp_line
			(start -0.67945 0.3048)
			(end -0.67945 -0.305054)
			(stroke
				(width 0.1)
				(type default)
			)
			(layer "F.Fab")
		)
		(fp_line
			(start -0.67945 -0.305054)
			(end -0.12065 -0.305054)
			(stroke
				(width 0.1)
				(type default)
			)
			(layer "F.Fab")
		)
		(pad "1" smd circle
			(at -0.40005 0 180)
			(size 0 0)
			(layers "F.Cu" "F.Mask" "F.Paste")
			(net "P3V3_AUX")
		)
		(pad "2" smd circle
			(at 0.40005 0 180)
			(size 0 0)
			(layers "F.Cu" "F.Mask" "F.Paste")
			(net "FM_BOARD_SKU_ID0")
		)
	)
	(footprint ""
		(layer "F.Cu")
		(at 15.113 -110.871 -90)
		(property "Reference" "R5366"
			(at 0 0 270)
			(layer "F.SilkS")
			(hide yes)
			(effects
				(font
					(size 1.27 1.27)
				)
			)
		)
		(property "Value" ""
			(at 0 0 270)
			(layer "F.Fab")
			(effects
				(font
					(size 1.27 1.27)
				)
			)
		)
		(duplicate_pad_numbers_are_jumpers no)
		(fp_line
			(start -0.7874 0.4064)
			(end -0.7874 -0.4064)
			(stroke
				(width 0.1524)
				(type default)
			)
			(layer "F.SilkS")
		)
		(fp_line
			(start 0.7874 0.4064)
			(end -0.7874 0.4064)
			(stroke
				(width 0.1524)
				(type default)
			)
			(layer "F.SilkS")
		)
		(fp_line
			(start -0.7874 -0.4064)
			(end 0.7874 -0.4064)
			(stroke
				(width 0.1524)
				(type default)
			)
			(layer "F.SilkS")
		)
		(fp_line
			(start 0.7874 -0.4064)
			(end 0.7874 0.4064)
			(stroke
				(width 0.1524)
				(type default)
			)
			(layer "F.SilkS")
		)
		(fp_line
			(start -0.67945 0.3048)
			(end -0.67945 -0.305054)
			(stroke
				(width 0.1)
				(type default)
			)
			(layer "F.Fab")
		)
		(fp_line
			(start -0.12065 0.3048)
			(end -0.67945 0.3048)
			(stroke
				(width 0.1)
				(type default)
			)
			(layer "F.Fab")
		)
		(fp_line
			(start 0.120396 0.3048)
			(end 0.120396 0.2794)
			(stroke
				(width 0.1)
				(type default)
			)
			(layer "F.Fab")
		)
		(fp_line
			(start 0.67945 0.3048)
			(end 0.120396 0.3048)
			(stroke
				(width 0.1)
				(type default)
			)
			(layer "F.Fab")
		)
		(fp_line
			(start -0.12065 0.2794)
			(end -0.12065 0.3048)
			(stroke
				(width 0.1)
				(type default)
			)
			(layer "F.Fab")
		)
		(fp_line
			(start 0.120396 0.2794)
			(end -0.12065 0.2794)
			(stroke
				(width 0.1)
				(type default)
			)
			(layer "F.Fab")
		)
		(fp_line
			(start -0.12065 -0.2794)
			(end 0.12065 -0.2794)
			(stroke
				(width 0.1)
				(type default)
			)
			(layer "F.Fab")
		)
		(fp_line
			(start 0.12065 -0.2794)
			(end 0.12065 -0.3048)
			(stroke
				(width 0.1)
				(type default)
			)
			(layer "F.Fab")
		)
		(fp_line
			(start 0.12065 -0.3048)
			(end 0.67945 -0.3048)
			(stroke
				(width 0.1)
				(type default)
			)
			(layer "F.Fab")
		)
		(fp_line
			(start 0.67945 -0.3048)
			(end 0.67945 0.3048)
			(stroke
				(width 0.1)
				(type default)
			)
			(layer "F.Fab")
		)
		(fp_line
			(start -0.67945 -0.305054)
			(end -0.12065 -0.305054)
			(stroke
				(width 0.1)
				(type default)
			)
			(layer "F.Fab")
		)
		(fp_line
			(start -0.12065 -0.305054)
			(end -0.12065 -0.2794)
			(stroke
				(width 0.1)
				(type default)
			)
			(layer "F.Fab")
		)
		(pad "1" smd rect
			(at -0.40005 0 90)
			(size 0.4572 0.508)
			(layers "F.Cu" "F.Mask" "F.Paste")
			(net "FAN_5_FAIL_LED_R_N")
		)
		(pad "2" smd rect
			(at 0.40005 0 90)
			(size 0.4572 0.508)
			(layers "F.Cu" "F.Mask" "F.Paste")
			(net "FAN_5_FAIL_R_LED_N")
		)
	)
	(footprint ""
		(layer "F.Cu")
		(at 36.322 -30.312868)
		(property "Reference" "D141"
			(at 3.302 -0.013462 0)
			(unlocked yes)
			(layer "F.SilkS")
			(effects
				(font
					(size 0.7874 0.5842)
					(thickness 0.1524)
				)
				(justify left)
			)
		)
		(property "Value" ""
			(at 0 0 0)
			(layer "F.Fab")
			(effects
				(font
					(size 1.27 1.27)
				)
			)
		)
		(duplicate_pad_numbers_are_jumpers no)
		(fp_line
			(start -1.651 -0.7112)
			(end 2.032 -0.7112)
			(stroke
				(width 0.1524)
				(type default)
			)
			(layer "F.SilkS")
		)
		(fp_line
			(start -1.651 0.7112)
			(end -1.651 -0.7112)
			(stroke
				(width 0.1524)
				(type default)
			)
			(layer "F.SilkS")
		)
		(fp_line
			(start -0.299974 -0.500126)
			(end -0.299974 0.500126)
			(stroke
				(width 0.1524)
				(type default)
			)
			(layer "F.SilkS")
		)
		(fp_line
			(start -0.299974 0.500126)
			(end 0.199898 0)
			(stroke
				(width 0.1524)
				(type default)
			)
			(layer "F.SilkS")
		)
		(fp_line
			(start 0.199898 0)
			(end -0.299974 -0.500126)
			(stroke
				(width 0.1524)
				(type default)
			)
			(layer "F.SilkS")
		)
		(fp_line
			(start 0.299974 -0.500126)
			(end 0.299974 0.500126)
			(stroke
				(width 0.1524)
				(type default)
			)
			(layer "F.SilkS")
		)
		(fp_line
			(start 1.651 -0.6858)
			(end 1.651 0.6858)
			(stroke
				(width 0.1524)
				(type default)
			)
			(layer "F.SilkS")
		)
		(fp_line
			(start 1.778 0.6858)
			(end 1.778 -0.6858)
			(stroke
				(width 0.1524)
				(type default)
			)
			(layer "F.SilkS")
		)
		(fp_line
			(start 1.905 -0.6858)
			(end 1.905 0.6858)
			(stroke
				(width 0.1524)
				(type default)
			)
			(layer "F.SilkS")
		)
		(fp_line
			(start 2.032 -0.7112)
			(end 2.032 0.7112)
			(stroke
				(width 0.1524)
				(type default)
			)
			(layer "F.SilkS")
		)
		(fp_line
			(start 2.032 0.7112)
			(end -1.651 0.7112)
			(stroke
				(width 0.1524)
				(type default)
			)
			(layer "F.SilkS")
		)
		(fp_line
			(start -1.35001 -0.225044)
			(end -0.899922 -0.225044)
			(stroke
				(width 0.1)
				(type default)
			)
			(layer "F.Fab")
		)
		(fp_line
			(start -1.35001 0.175006)
			(end -1.35001 -0.225044)
			(stroke
				(width 0.1)
				(type default)
			)
			(layer "F.Fab")
		)
		(fp_line
			(start -0.899922 -0.700024)
			(end 0.899922 -0.700024)
			(stroke
				(width 0.1)
				(type default)
			)
			(layer "F.Fab")
		)
		(fp_line
			(start -0.899922 -0.225044)
			(end -0.899922 -0.700024)
			(stroke
				(width 0.1)
				(type default)
			)
			(layer "F.Fab")
		)
		(fp_line
			(start -0.899922 0.175006)
			(end -1.35001 0.175006)
			(stroke
				(width 0.1)
				(type default)
			)
			(layer "F.Fab")
		)
		(fp_line
			(start -0.899922 0.700024)
			(end -0.899922 0.175006)
			(stroke
				(width 0.1)
				(type default)
			)
			(layer "F.Fab")
		)
		(fp_line
			(start -0.299974 -0.500126)
			(end -0.299974 0.500126)
			(stroke
				(width 0.1)
				(type default)
			)
			(layer "F.Fab")
		)
		(fp_line
			(start -0.299974 0.500126)
			(end 0.199898 0)
			(stroke
				(width 0.1)
				(type default)
			)
			(layer "F.Fab")
		)
		(fp_line
			(start 0.199898 0)
			(end -0.299974 -0.500126)
			(stroke
				(width 0.1)
				(type default)
			)
			(layer "F.Fab")
		)
		(fp_line
			(start 0.299974 -0.500126)
			(end 0.299974 0.500126)
			(stroke
				(width 0.1)
				(type default)
			)
			(layer "F.Fab")
		)
		(fp_line
			(start 0.899922 -0.700024)
			(end 0.899922 -0.225044)
			(stroke
				(width 0.1)
				(type default)
			)
			(layer "F.Fab")
		)
		(fp_line
			(start 0.899922 -0.225044)
			(end 1.35001 -0.225044)
			(stroke
				(width 0.1)
				(type default)
			)
			(layer "F.Fab")
		)
		(fp_line
			(start 0.899922 0.175006)
			(end 0.899922 0.700024)
			(stroke
				(width 0.1)
				(type default)
			)
			(layer "F.Fab")
		)
		(fp_line
			(start 0.899922 0.700024)
			(end -0.899922 0.700024)
			(stroke
				(width 0.1)
				(type default)
			)
			(layer "F.Fab")
		)
		(fp_line
			(start 1.35001 -0.225044)
			(end 1.35001 0.175006)
			(stroke
				(width 0.1)
				(type default)
			)
			(layer "F.Fab")
		)
		(fp_line
			(start 1.35001 0.175006)
			(end 0.899922 0.175006)
			(stroke
				(width 0.1)
				(type default)
			)
			(layer "F.Fab")
		)
		(fp_text user "+"
			(at -2.921 0.372618 0)
			(unlocked yes)
			(layer "F.SilkS")
			(effects
				(font
					(size 1.905 1.4224)
					(thickness 0.1524)
				)
				(justify left)
			)
		)
		(fp_text user "-"
			(at 1.8288 -0.24765 0)
			(unlocked yes)
			(layer "F.SilkS")
			(effects
				(font
					(size 1.905 1.4224)
					(thickness 0.1524)
				)
				(justify left)
			)
		)
		(fp_text user "+"
			(at -2.794 -0.19685 0)
			(unlocked yes)
			(layer "F.Fab")
			(effects
				(font
					(size 1.905 1.4224)
					(thickness 0.1524)
				)
				(justify left)
			)
		)
		(fp_text user "-"
			(at 1.8288 -0.24765 0)
			(unlocked yes)
			(layer "F.Fab")
			(effects
				(font
					(size 1.905 1.4224)
					(thickness 0.1524)
				)
				(justify left)
			)
		)
		(pad "1" smd rect
			(at -1.0922 0 180)
			(size 0.8128 0.8636)
			(layers "F.Cu" "F.Mask" "F.Paste")
			(net "FAN_3_TACH_IL_R")
		)
		(pad "2" smd rect
			(at 1.0922 0)
			(size 0.8128 0.8636)
			(layers "F.Cu" "F.Mask" "F.Paste")
			(net "FAN_3_TACH_IL_D")
		)
	)
)
